# T6G (Grand Teton) — schematic netlist excerpt (pin names and nets, part order shuffled) for the footprints in the layout excerpt that follows; sources: Cadence DE-HDL packaged netlist, KiCad conversion of 04192023_DAF0TMB3IC0_F0TG_MB_C_brd_V02_OCP.brd

PL56  Q_INDUCTOR  100NH/16A IND  pkg SMLF  page 225 : \1\ = SW_P12V_AUX_PVDD11_S3_P1_FLT ; \2\ = P12V_AUX
PC644  Q_CAP  10UF 6.3V 20% X6S  pkg C0402  page 224 : A = PVDD11_S3_P1_VCCS ; B = GND

(kicad_pcb
	(version 20260206)
	(generator "pcbnew")
	(generator_version "10.0")
	(general
		(thickness 1.6)
		(legacy_teardrops no)
	)
	(paper "A4")
	(title_block
		(title "04192023_DAF0TMB3IC0_F0TG_MB_C_brd_V02_OCP.brd")
		(comment 1 "Grand Teton / footprints 1300-1301 of 8354")
	)
	(layers
		(0 "F.Cu" signal "TOP")
		(4 "In1.Cu" signal "GND")
		(6 "In2.Cu" signal "IN1")
		(8 "In3.Cu" signal "GND1")
		(10 "In4.Cu" signal "IN2")
		(12 "In5.Cu" signal "GND2")
		(14 "In6.Cu" signal "IN3")
		(16 "In7.Cu" signal "GND3")
		(18 "In8.Cu" signal "VCC")
		(20 "In9.Cu" signal "VCC1")
		(22 "In10.Cu" signal "GND4")
		(24 "In11.Cu" signal "IN4")
		(26 "In12.Cu" signal "GND5")
		(28 "In13.Cu" signal "IN5")
		(30 "In14.Cu" signal "GND6")
		(32 "In15.Cu" signal "IN6")
		(34 "In16.Cu" signal "GND7")
		(2 "B.Cu" signal "BOTTOM")
		(9 "F.Adhes" user "F.Adhesive")
		(11 "B.Adhes" user "B.Adhesive")
		(13 "F.Paste" user "Package Geometry/Pastemask Top")
		(15 "B.Paste" user "Package Geometry/Pastemask Bottom")
		(5 "F.SilkS" user "Ref Des/Silkscreen Top")
		(7 "B.SilkS" user "Ref Des/Silkscreen Bottom")
		(1 "F.Mask" user "Board Geometry/Soldermask Top")
		(3 "B.Mask" user "Board Geometry/Soldermask Bottom")
		(17 "Dwgs.User" user "User.Drawings")
		(19 "Cmts.User" user "User.Comments")
		(21 "Eco1.User" user "User.Eco1")
		(23 "Eco2.User" user "User.Eco2")
		(25 "Edge.Cuts" user "Board Geometry/Outline")
		(27 "Margin" user)
		(31 "F.CrtYd" user "Package Geometry/Place Bound Top")
		(29 "B.CrtYd" user "Package Geometry/Place Bound Bottom")
		(35 "F.Fab" user "Ref Des/Assembly Top")
		(33 "B.Fab" user "Ref Des/Assembly Bottom")
	)
	(footprint ""
		(layer "F.Cu")
		(at 183.269636 -361.600242 180)
		(property "Reference" "PL56"
			(at 0.643636 2.863088 0)
			(unlocked yes)
			(layer "F.SilkS")
			(effects
				(font
					(size 0.7874 0.5842)
					(thickness 0.1524)
				)
				(justify left)
			)
		)
		(property "Value" ""
			(at 0 0 180)
			(layer "F.Fab")
			(effects
				(font
					(size 1.27 1.27)
				)
			)
		)
		(duplicate_pad_numbers_are_jumpers no)
		(fp_line
			(start 2.249932 2.249932)
			(end -2.249932 2.249932)
			(stroke
				(width 0.1524)
				(type default)
			)
			(layer "F.SilkS")
		)
		(fp_line
			(start 2.249932 1.3843)
			(end 2.249932 2.249932)
			(stroke
				(width 0.1524)
				(type default)
			)
			(layer "F.SilkS")
		)
		(fp_line
			(start 2.249932 -2.249932)
			(end 2.249932 -1.3843)
			(stroke
				(width 0.1524)
				(type default)
			)
			(layer "F.SilkS")
		)
		(fp_line
			(start -2.249932 2.249932)
			(end -2.249932 1.3843)
			(stroke
				(width 0.1524)
				(type default)
			)
			(layer "F.SilkS")
		)
		(fp_line
			(start -2.249932 -1.3843)
			(end -2.249932 -2.249932)
			(stroke
				(width 0.1524)
				(type default)
			)
			(layer "F.SilkS")
		)
		(fp_line
			(start -2.249932 -2.249932)
			(end 2.249932 -2.249932)
			(stroke
				(width 0.1524)
				(type default)
			)
			(layer "F.SilkS")
		)
		(fp_line
			(start 2.249932 2.249932)
			(end -2.249932 2.249932)
			(stroke
				(width 0.1)
				(type default)
			)
			(layer "F.Fab")
		)
		(fp_line
			(start 2.249932 -2.249932)
			(end 2.249932 2.249932)
			(stroke
				(width 0.1)
				(type default)
			)
			(layer "F.Fab")
		)
		(fp_line
			(start -2.249932 2.249932)
			(end -2.249932 -2.249932)
			(stroke
				(width 0.1)
				(type default)
			)
			(layer "F.Fab")
		)
		(fp_line
			(start -2.249932 -2.249932)
			(end 2.249932 -2.249932)
			(stroke
				(width 0.1)
				(type default)
			)
			(layer "F.Fab")
		)
		(pad "1" smd rect
			(at -1.82499 0 180)
			(size 1.0668 2.5146)
			(layers "F.Cu" "F.Mask" "F.Paste")
			(net "SW_P12V_AUX_PVDD11_S3_P1_FLT")
		)
		(pad "2" smd rect
			(at 1.82499 0 180)
			(size 1.0668 2.5146)
			(layers "F.Cu" "F.Mask" "F.Paste")
			(net "P12V_AUX")
		)
	)
	(footprint ""
		(layer "F.Cu")
		(at 164.45103 -352.658934 90)
		(property "Reference" "PC644"
			(at 0 0 90)
			(layer "F.SilkS")
			(hide yes)
			(effects
				(font
					(size 1.27 1.27)
				)
			)
		)
		(property "Value" ""
			(at 0 0 90)
			(layer "F.Fab")
			(effects
				(font
					(size 1.27 1.27)
				)
			)
		)
		(duplicate_pad_numbers_are_jumpers no)
		(fp_line
			(start 0.7874 -0.4064)
			(end 0.7874 0.4064)
			(stroke
				(width 0.1524)
				(type default)
			)
			(layer "F.SilkS")
		)
		(fp_line
			(start -0.7874 -0.4064)
			(end 0.7874 -0.4064)
			(stroke
				(width 0.1524)
				(type default)
			)
			(layer "F.SilkS")
		)
		(fp_line
			(start 0.7874 0.4064)
			(end -0.7874 0.4064)
			(stroke
				(width 0.1524)
				(type default)
			)
			(layer "F.SilkS")
		)
		(fp_line
			(start -0.7874 0.4064)
			(end -0.7874 -0.4064)
			(stroke
				(width 0.1524)
				(type default)
			)
			(layer "F.SilkS")
		)
		(fp_line
			(start -0.12065 -0.305054)
			(end -0.12065 -0.2794)
			(stroke
				(width 0.1)
				(type default)
			)
			(layer "F.Fab")
		)
		(fp_line
			(start -0.67945 -0.305054)
			(end -0.12065 -0.305054)
			(stroke
				(width 0.1)
				(type default)
			)
			(layer "F.Fab")
		)
		(fp_line
			(start 0.67945 -0.3048)
			(end 0.67945 0.3048)
			(stroke
				(width 0.1)
				(type default)
			)
			(layer "F.Fab")
		)
		(fp_line
			(start 0.12065 -0.3048)
			(end 0.67945 -0.3048)
			(stroke
				(width 0.1)
				(type default)
			)
			(layer "F.Fab")
		)
		(fp_line
			(start 0.12065 -0.2794)
			(end 0.12065 -0.3048)
			(stroke
				(width 0.1)
				(type default)
			)
			(layer "F.Fab")
		)
		(fp_line
			(start -0.12065 -0.2794)
			(end 0.12065 -0.2794)
			(stroke
				(width 0.1)
				(type default)
			)
			(layer "F.Fab")
		)
		(fp_line
			(start 0.120396 0.2794)
			(end -0.12065 0.2794)
			(stroke
				(width 0.1)
				(type default)
			)
			(layer "F.Fab")
		)
		(fp_line
			(start -0.12065 0.2794)
			(end -0.12065 0.3048)
			(stroke
				(width 0.1)
				(type default)
			)
			(layer "F.Fab")
		)
		(fp_line
			(start 0.67945 0.3048)
			(end 0.120396 0.3048)
			(stroke
				(width 0.1)
				(type default)
			)
			(layer "F.Fab")
		)
		(fp_line
			(start 0.120396 0.3048)
			(end 0.120396 0.2794)
			(stroke
				(width 0.1)
				(type default)
			)
			(layer "F.Fab")
		)
		(fp_line
			(start -0.12065 0.3048)
			(end -0.67945 0.3048)
			(stroke
				(width 0.1)
				(type default)
			)
			(layer "F.Fab")
		)
		(fp_line
			(start -0.67945 0.3048)
			(end -0.67945 -0.305054)
			(stroke
				(width 0.1)
				(type default)
			)
			(layer "F.Fab")
		)
		(pad "1" smd circle
			(at -0.40005 0 90)
			(size 0 0)
			(layers "F.Cu" "F.Mask" "F.Paste")
			(net "PVDD11_S3_P1_VCCS")
		)
		(pad "2" smd circle
			(at 0.40005 0 90)
			(size 0 0)
			(layers "F.Cu" "F.Mask" "F.Paste")
			(net "GND")
		)
	)
)
